(kicad_pcb
	(version 20260206)
	(generator "pcbnew")
	(generator_version "10.0")
	(general
		(thickness 1.6)
		(legacy_teardrops no)
	)
	(paper "A4")
	(title_block
		(title "peb — Lightning_PEB_BRD.brd")
		(comment 1 "Lightning (Wiwynn / Facebook NVMe JBOF) / footprints 1145-1152 of 2563")
	)
	(layers
		(0 "F.Cu" signal "TOP")
		(4 "In1.Cu" signal "L2GND")
		(6 "In2.Cu" signal "L3")
		(8 "In3.Cu" signal "L4VCC")
		(10 "In4.Cu" signal "L5VCC")
		(12 "In5.Cu" signal "L6")
		(14 "In6.Cu" signal "L7GND")
		(2 "B.Cu" signal "BOTTOM")
		(9 "F.Adhes" user "F.Adhesive")
		(11 "B.Adhes" user "B.Adhesive")
		(13 "F.Paste" user "Package Geometry/Pastemask Top")
		(15 "B.Paste" user "Package Geometry/Pastemask Bottom")
		(5 "F.SilkS" user "Ref Des/Silkscreen Top")
		(7 "B.SilkS" user "Ref Des/Silkscreen Bottom")
		(1 "F.Mask" user "Board Geometry/Soldermask Top")
		(3 "B.Mask" user "Board Geometry/Soldermask Bottom")
		(17 "Dwgs.User" user "User.Drawings")
		(19 "Cmts.User" user "User.Comments")
		(21 "Eco1.User" user "User.Eco1")
		(23 "Eco2.User" user "User.Eco2")
		(25 "Edge.Cuts" user "Board Geometry/Outline")
		(27 "Margin" user)
		(31 "F.CrtYd" user "Package Geometry/Place Bound Top")
		(29 "B.CrtYd" user "Package Geometry/Place Bound Bottom")
		(35 "F.Fab" user "Ref Des/Assembly Top")
		(33 "B.Fab" user "Ref Des/Assembly Bottom")
	)
	(footprint ""
		(layer "F.Cu")
		(at 36.842954 -163.559744 90)
		(property "Reference" "C179"
			(at 0 0 90)
			(layer "F.SilkS")
			(hide yes)
			(effects
				(font
					(size 1.27 1.27)
				)
			)
		)
		(property "Value" "SCD01U25V2KX-3GP"
			(at 1.1811 -2.7051 90)
			(unlocked yes)
			(layer "F.Fab")
			(hide yes)
			(effects
				(font
					(size 1.016 1.016)
					(thickness 0.1524)
				)
			)
		)
		(property "Device Type" "C402H22"
			(at 1.1811 -4.2291 90)
			(unlocked yes)
			(layer "F.Fab")
			(hide yes)
			(effects
				(font
					(size 1.016 1.016)
					(thickness 0.1524)
				)
			)
		)
		(duplicate_pad_numbers_are_jumpers no)
		(fp_rect
			(start -0.4318 0.9525)
			(end 0.4318 -0.9525)
			(stroke
				(width 0)
				(type default)
			)
			(fill no)
			(layer "F.CrtYd")
		)
		(fp_rect
			(start -0.4318 0.9525)
			(end 0.4318 -0.9525)
			(stroke
				(width 0)
				(type default)
			)
			(fill no)
			(layer "F.Fab")
		)
		(pad "1" smd custom
			(at 0 -0.4445 90)
			(size 0.1524 0.1524)
			(layers "F.Cu" "F.Mask" "F.Paste")
			(net "DDR_VREF")
			(options
				(clearance outline)
				(anchor circle)
			)
			(primitives
				(gr_poly
					(pts
						(arc
							(start 0.3048 -0.2032)
							(mid 0.275042 -0.275042)
							(end 0.2032 -0.3048)
						)
						(arc
							(start -0.2032 -0.3048)
							(mid -0.275042 -0.275042)
							(end -0.3048 -0.2032)
						)
						(arc
							(start -0.3048 0.2032)
							(mid -0.275042 0.275042)
							(end -0.2032 0.3048)
						)
						(arc
							(start 0.2032 0.3048)
							(mid 0.275042 0.275042)
							(end 0.3048 0.2032)
						)
					)
					(width 0)
					(fill yes)
				)
			)
		)
		(pad "2" smd custom
			(at 0 0.4445 90)
			(size 0.1524 0.1524)
			(layers "F.Cu" "F.Mask" "F.Paste")
			(net "GND")
			(options
				(clearance outline)
				(anchor circle)
			)
			(primitives
				(gr_poly
					(pts
						(arc
							(start 0.3048 -0.2032)
							(mid 0.275042 -0.275042)
							(end 0.2032 -0.3048)
						)
						(arc
							(start -0.2032 -0.3048)
							(mid -0.275042 -0.275042)
							(end -0.3048 -0.2032)
						)
						(arc
							(start -0.3048 0.2032)
							(mid -0.275042 0.275042)
							(end -0.2032 0.3048)
						)
						(arc
							(start 0.2032 0.3048)
							(mid 0.275042 0.275042)
							(end 0.3048 0.2032)
						)
					)
					(width 0)
					(fill yes)
				)
			)
		)
	)
	(footprint ""
		(layer "F.Cu")
		(at 16.256 -143.383 90)
		(property "Reference" "L6"
			(at 0 0 90)
			(layer "F.SilkS")
			(hide yes)
			(effects
				(font
					(size 1.27 1.27)
				)
			)
		)
		(property "Value" "MMZ2012S601ATA1N-GP"
			(at 0 -4.2418 90)
			(unlocked yes)
			(layer "F.Fab")
			(hide yes)
			(effects
				(font
					(size 1.016 1.016)
					(thickness 0.1524)
				)
			)
		)
		(property "Device Type" "L805H42"
			(at 0 -5.7912 90)
			(unlocked yes)
			(layer "F.Fab")
			(hide yes)
			(effects
				(font
					(size 1.016 1.016)
					(thickness 0.1524)
				)
			)
		)
		(duplicate_pad_numbers_are_jumpers no)
		(fp_line
			(start 0.889 -1.7018)
			(end 0.889 1.7018)
			(stroke
				(width 0.1524)
				(type default)
			)
			(layer "F.SilkS")
		)
		(fp_line
			(start -0.889 -1.7018)
			(end 0.889 -1.7018)
			(stroke
				(width 0.1524)
				(type default)
			)
			(layer "F.SilkS")
		)
		(fp_line
			(start 0.889 1.7018)
			(end -0.889 1.7018)
			(stroke
				(width 0.1524)
				(type default)
			)
			(layer "F.SilkS")
		)
		(fp_line
			(start -0.889 1.7018)
			(end -0.889 -1.7018)
			(stroke
				(width 0.1524)
				(type default)
			)
			(layer "F.SilkS")
		)
		(fp_rect
			(start -0.9652 1.778)
			(end 0.9652 -1.778)
			(stroke
				(width 0)
				(type default)
			)
			(fill no)
			(layer "F.CrtYd")
		)
		(fp_rect
			(start -0.9652 1.778)
			(end 0.9652 -1.778)
			(stroke
				(width 0)
				(type default)
			)
			(fill no)
			(layer "F.Fab")
		)
		(pad "1" smd rect
			(at 0 -0.9652 90)
			(size 1.397 1.143)
			(layers "F.Cu" "F.Mask" "F.Paste")
			(net "P1V26_STBY")
		)
		(pad "2" smd rect
			(at 0 0.9652 90)
			(size 1.397 1.143)
			(layers "F.Cu" "F.Mask" "F.Paste")
			(net "V1PLLAV12")
		)
	)
	(footprint ""
		(layer "F.Cu")
		(at 27.686 -142.621 -90)
		(property "Reference" "R449"
			(at 0 0 270)
			(layer "F.SilkS")
			(hide yes)
			(effects
				(font
					(size 1.27 1.27)
				)
			)
		)
		(property "Value" "0R2J-2-GP"
			(at 0.064008 -3.993896 270)
			(unlocked yes)
			(layer "F.Fab")
			(hide yes)
			(effects
				(font
					(size 1.016 1.016)
					(thickness 0.1524)
				)
			)
		)
		(property "Device Type" "R402H16"
			(at 0.064008 -5.517896 270)
			(unlocked yes)
			(layer "F.Fab")
			(hide yes)
			(effects
				(font
					(size 1.016 1.016)
					(thickness 0.1524)
				)
			)
		)
		(duplicate_pad_numbers_are_jumpers no)
		(fp_line
			(start -0.508 -0.9398)
			(end -0.508 0.9398)
			(stroke
				(width 0.1524)
				(type default)
			)
			(layer "F.SilkS")
		)
		(fp_line
			(start 0.508 -0.9398)
			(end -0.508 -0.9398)
			(stroke
				(width 0.1524)
				(type default)
			)
			(layer "F.SilkS")
		)
		(fp_rect
			(start -0.508 0.9398)
			(end 0.508 -0.9398)
			(stroke
				(width 0)
				(type default)
			)
			(fill no)
			(layer "F.CrtYd")
		)
		(fp_rect
			(start -0.508 0.9398)
			(end 0.508 -0.9398)
			(stroke
				(width 0)
				(type default)
			)
			(fill no)
			(layer "F.Fab")
		)
		(pad "1" smd custom
			(at 0 -0.4445 270)
			(size 0.1397 0.1397)
			(layers "F.Cu" "F.Mask" "F.Paste")
			(net "BMC_USB2_HDP")
			(options
				(clearance outline)
				(anchor circle)
			)
			(primitives
				(gr_poly
					(pts
						(arc
							(start -0.1778 -0.2794)
							(mid -0.249642 -0.249642)
							(end -0.2794 -0.1778)
						)
						(arc
							(start -0.2794 0.1778)
							(mid -0.249642 0.249642)
							(end -0.1778 0.2794)
						)
						(arc
							(start 0.1778 0.2794)
							(mid 0.249642 0.249642)
							(end 0.2794 0.1778)
						)
						(arc
							(start 0.2794 -0.1778)
							(mid 0.249642 -0.249642)
							(end 0.1778 -0.2794)
						)
					)
					(width 0)
					(fill yes)
				)
			)
		)
		(pad "2" smd custom
			(at 0 0.4445 270)
			(size 0.1397 0.1397)
			(layers "F.Cu" "F.Mask" "F.Paste")
			(net "USB2_BMC_DP")
			(options
				(clearance outline)
				(anchor circle)
			)
			(primitives
				(gr_poly
					(pts
						(arc
							(start -0.1778 -0.2794)
							(mid -0.249642 -0.249642)
							(end -0.2794 -0.1778)
						)
						(arc
							(start -0.2794 0.1778)
							(mid -0.249642 0.249642)
							(end -0.1778 0.2794)
						)
						(arc
							(start 0.1778 0.2794)
							(mid 0.249642 0.249642)
							(end 0.2794 0.1778)
						)
						(arc
							(start 0.2794 -0.1778)
							(mid 0.249642 -0.249642)
							(end 0.1778 -0.2794)
						)
					)
					(width 0)
					(fill yes)
				)
			)
		)
	)
	(footprint ""
		(layer "F.Cu")
		(at 27.3812 -58.4454 90)
		(property "Reference" "R2949"
			(at 0 0 90)
			(layer "F.SilkS")
			(hide yes)
			(effects
				(font
					(size 1.27 1.27)
				)
			)
		)
		(property "Value" "0R2J-2-GP"
			(at 0.064008 -3.993896 90)
			(unlocked yes)
			(layer "F.Fab")
			(hide yes)
			(effects
				(font
					(size 1.016 1.016)
					(thickness 0.1524)
				)
			)
		)
		(property "Device Type" "R402H16"
			(at 0.064008 -5.517896 90)
			(unlocked yes)
			(layer "F.Fab")
			(hide yes)
			(effects
				(font
					(size 1.016 1.016)
					(thickness 0.1524)
				)
			)
		)
		(duplicate_pad_numbers_are_jumpers no)
		(fp_line
			(start 0.508 -0.9398)
			(end -0.508 -0.9398)
			(stroke
				(width 0.1524)
				(type default)
			)
			(layer "F.SilkS")
		)
		(fp_line
			(start -0.508 -0.9398)
			(end -0.508 0.9398)
			(stroke
				(width 0.1524)
				(type default)
			)
			(layer "F.SilkS")
		)
		(fp_rect
			(start -0.508 0.9398)
			(end 0.508 -0.9398)
			(stroke
				(width 0)
				(type default)
			)
			(fill no)
			(layer "F.CrtYd")
		)
		(fp_rect
			(start -0.508 0.9398)
			(end 0.508 -0.9398)
			(stroke
				(width 0)
				(type default)
			)
			(fill no)
			(layer "F.Fab")
		)
		(pad "1" smd custom
			(at 0 -0.4445 90)
			(size 0.1397 0.1397)
			(layers "F.Cu" "F.Mask" "F.Paste")
			(net "I2C_TPM_SDA")
			(options
				(clearance outline)
				(anchor circle)
			)
			(primitives
				(gr_poly
					(pts
						(arc
							(start -0.1778 -0.2794)
							(mid -0.249642 -0.249642)
							(end -0.2794 -0.1778)
						)
						(arc
							(start -0.2794 0.1778)
							(mid -0.249642 0.249642)
							(end -0.1778 0.2794)
						)
						(arc
							(start 0.1778 0.2794)
							(mid 0.249642 0.249642)
							(end 0.2794 0.1778)
						)
						(arc
							(start 0.2794 -0.1778)
							(mid 0.249642 -0.249642)
							(end 0.1778 -0.2794)
						)
					)
					(width 0)
					(fill yes)
				)
			)
		)
		(pad "2" smd custom
			(at 0 0.4445 90)
			(size 0.1397 0.1397)
			(layers "F.Cu" "F.Mask" "F.Paste")
			(net "BMC_I2C5_D_PEB_DEVICE_SDA")
			(options
				(clearance outline)
				(anchor circle)
			)
			(primitives
				(gr_poly
					(pts
						(arc
							(start -0.1778 -0.2794)
							(mid -0.249642 -0.249642)
							(end -0.2794 -0.1778)
						)
						(arc
							(start -0.2794 0.1778)
							(mid -0.249642 0.249642)
							(end -0.1778 0.2794)
						)
						(arc
							(start 0.1778 0.2794)
							(mid 0.249642 0.249642)
							(end 0.2794 0.1778)
						)
						(arc
							(start 0.2794 -0.1778)
							(mid 0.249642 -0.249642)
							(end 0.1778 -0.2794)
						)
					)
					(width 0)
					(fill yes)
				)
			)
		)
	)
	(footprint ""
		(layer "F.Cu")
		(at 273.939 -15.367 90)
		(property "Reference" "C6"
			(at 0 0 90)
			(layer "F.SilkS")
			(hide yes)
			(effects
				(font
					(size 1.27 1.27)
				)
			)
		)
		(property "Value" "SCD22U10V2KX-1GP"
			(at 1.1811 -2.7051 90)
			(unlocked yes)
			(layer "F.Fab")
			(hide yes)
			(effects
				(font
					(size 1.016 1.016)
					(thickness 0.1524)
				)
			)
		)
		(property "Device Type" "C402H22"
			(at 1.1811 -4.2291 90)
			(unlocked yes)
			(layer "F.Fab")
			(hide yes)
			(effects
				(font
					(size 1.016 1.016)
					(thickness 0.1524)
				)
			)
		)
		(duplicate_pad_numbers_are_jumpers no)
		(fp_rect
			(start -0.4318 0.9525)
			(end 0.4318 -0.9525)
			(stroke
				(width 0)
				(type default)
			)
			(fill no)
			(layer "F.CrtYd")
		)
		(fp_rect
			(start -0.4318 0.9525)
			(end 0.4318 -0.9525)
			(stroke
				(width 0)
				(type default)
			)
			(fill no)
			(layer "F.Fab")
		)
		(pad "1" smd custom
			(at 0 -0.4445 90)
			(size 0.1524 0.1524)
			(layers "F.Cu" "F.Mask" "F.Paste")
			(net "PCIE_TX_CAP_N1")
			(options
				(clearance outline)
				(anchor circle)
			)
			(primitives
				(gr_poly
					(pts
						(arc
							(start 0.3048 -0.2032)
							(mid 0.275042 -0.275042)
							(end 0.2032 -0.3048)
						)
						(arc
							(start -0.2032 -0.3048)
							(mid -0.275042 -0.275042)
							(end -0.3048 -0.2032)
						)
						(arc
							(start -0.3048 0.2032)
							(mid -0.275042 0.275042)
							(end -0.2032 0.3048)
						)
						(arc
							(start 0.2032 0.3048)
							(mid 0.275042 0.275042)
							(end 0.3048 0.2032)
						)
					)
					(width 0)
					(fill yes)
				)
			)
		)
		(pad "2" smd custom
			(at 0 0.4445 90)
			(size 0.1524 0.1524)
			(layers "F.Cu" "F.Mask" "F.Paste")
			(net "PCIE_TX_N1")
			(options
				(clearance outline)
				(anchor circle)
			)
			(primitives
				(gr_poly
					(pts
						(arc
							(start 0.3048 -0.2032)
							(mid 0.275042 -0.275042)
							(end 0.2032 -0.3048)
						)
						(arc
							(start -0.2032 -0.3048)
							(mid -0.275042 -0.275042)
							(end -0.3048 -0.2032)
						)
						(arc
							(start -0.3048 0.2032)
							(mid -0.275042 0.275042)
							(end -0.2032 0.3048)
						)
						(arc
							(start 0.2032 0.3048)
							(mid 0.275042 0.275042)
							(end 0.3048 0.2032)
						)
					)
					(width 0)
					(fill yes)
				)
			)
		)
	)
	(footprint ""
		(layer "F.Cu")
		(at 194.608196 -212.420454 180)
		(property "Reference" "C120"
			(at 0 0 180)
			(layer "F.SilkS")
			(hide yes)
			(effects
				(font
					(size 1.27 1.27)
				)
			)
		)
		(property "Value" "SCD22U10V2KX-1GP"
			(at 1.1811 -2.7051 180)
			(unlocked yes)
			(layer "F.Fab")
			(hide yes)
			(effects
				(font
					(size 1.016 1.016)
					(thickness 0.1524)
				)
			)
		)
		(property "Device Type" "C402H22"
			(at 1.1811 -4.2291 180)
			(unlocked yes)
			(layer "F.Fab")
			(hide yes)
			(effects
				(font
					(size 1.016 1.016)
					(thickness 0.1524)
				)
			)
		)
		(duplicate_pad_numbers_are_jumpers no)
		(fp_rect
			(start -0.4318 0.9525)
			(end 0.4318 -0.9525)
			(stroke
				(width 0)
				(type default)
			)
			(fill no)
			(layer "F.CrtYd")
		)
		(fp_rect
			(start -0.4318 0.9525)
			(end 0.4318 -0.9525)
			(stroke
				(width 0)
				(type default)
			)
			(fill no)
			(layer "F.Fab")
		)
		(pad "1" smd custom
			(at 0 -0.4445 180)
			(size 0.1524 0.1524)
			(layers "F.Cu" "F.Mask" "F.Paste")
			(net "PCIE_TX_CAP_N44")
			(options
				(clearance outline)
				(anchor circle)
			)
			(primitives
				(gr_poly
					(pts
						(arc
							(start 0.3048 -0.2032)
							(mid 0.275042 -0.275042)
							(end 0.2032 -0.3048)
						)
						(arc
							(start -0.2032 -0.3048)
							(mid -0.275042 -0.275042)
							(end -0.3048 -0.2032)
						)
						(arc
							(start -0.3048 0.2032)
							(mid -0.275042 0.275042)
							(end -0.2032 0.3048)
						)
						(arc
							(start 0.2032 0.3048)
							(mid 0.275042 0.275042)
							(end 0.3048 0.2032)
						)
					)
					(width 0)
					(fill yes)
				)
			)
		)
		(pad "2" smd custom
			(at 0 0.4445 180)
			(size 0.1524 0.1524)
			(layers "F.Cu" "F.Mask" "F.Paste")
			(net "PCIE_TX_N44")
			(options
				(clearance outline)
				(anchor circle)
			)
			(primitives
				(gr_poly
					(pts
						(arc
							(start 0.3048 -0.2032)
							(mid 0.275042 -0.275042)
							(end 0.2032 -0.3048)
						)
						(arc
							(start -0.2032 -0.3048)
							(mid -0.275042 -0.275042)
							(end -0.3048 -0.2032)
						)
						(arc
							(start -0.3048 0.2032)
							(mid -0.275042 0.275042)
							(end -0.2032 0.3048)
						)
						(arc
							(start 0.2032 0.3048)
							(mid 0.275042 0.275042)
							(end 0.3048 0.2032)
						)
					)
					(width 0)
					(fill yes)
				)
			)
		)
	)
	(footprint ""
		(layer "F.Cu")
		(at 78.191106 -86.487254 -90)
		(property "Reference" "R481"
			(at 0 0 270)
			(layer "F.SilkS")
			(hide yes)
			(effects
				(font
					(size 1.27 1.27)
				)
			)
		)
		(property "Value" "200R3F-GP"
			(at -0.0254 -2.5146 270)
			(unlocked yes)
			(layer "F.Fab")
			(hide yes)
			(effects
				(font
					(size 1.016 1.016)
					(thickness 0.1524)
				)
			)
		)
		(property "Device Type" "R603H22"
			(at -0.0254 -4.0386 270)
			(unlocked yes)
			(layer "F.Fab")
			(hide yes)
			(effects
				(font
					(size 1.016 1.016)
					(thickness 0.1524)
				)
			)
		)
		(duplicate_pad_numbers_are_jumpers no)
		(fp_line
			(start -0.4826 0)
			(end -0.2032 0)
			(stroke
				(width 0.2032)
				(type default)
			)
			(layer "F.SilkS")
		)
		(fp_line
			(start 0.2032 0)
			(end 0.4826 0)
			(stroke
				(width 0.2032)
				(type default)
			)
			(layer "F.SilkS")
		)
		(fp_rect
			(start -0.5842 1.3335)
			(end 0.5842 -1.3335)
			(stroke
				(width 0)
				(type default)
			)
			(fill no)
			(layer "F.CrtYd")
		)
		(fp_rect
			(start -0.5842 1.3335)
			(end 0.5842 -1.3335)
			(stroke
				(width 0)
				(type default)
			)
			(fill no)
			(layer "F.Fab")
		)
		(pad "1" smd custom
			(at 0 -0.762 270)
			(size 0.2159 0.2159)
			(layers "F.Cu" "F.Mask" "F.Paste")
			(net "P3V3_STBY")
			(options
				(clearance outline)
				(anchor circle)
			)
			(primitives
				(gr_poly
					(pts
						(arc
							(start -0.3302 -0.4318)
							(mid -0.402042 -0.402042)
							(end -0.4318 -0.3302)
						)
						(arc
							(start -0.4318 0.3302)
							(mid -0.402042 0.402042)
							(end -0.3302 0.4318)
						)
						(arc
							(start 0.3302 0.4318)
							(mid 0.402042 0.402042)
							(end 0.4318 0.3302)
						)
						(arc
							(start 0.4318 -0.3302)
							(mid 0.402042 -0.402042)
							(end 0.3302 -0.4318)
						)
					)
					(width 0)
					(fill yes)
				)
			)
		)
		(pad "2" smd custom
			(at 0 0.762 270)
			(size 0.2159 0.2159)
			(layers "F.Cu" "F.Mask" "F.Paste")
			(net "HB_A_OUT")
			(options
				(clearance outline)
				(anchor circle)
			)
			(primitives
				(gr_poly
					(pts
						(arc
							(start -0.3302 -0.4318)
							(mid -0.402042 -0.402042)
							(end -0.4318 -0.3302)
						)
						(arc
							(start -0.4318 0.3302)
							(mid -0.402042 0.402042)
							(end -0.3302 0.4318)
						)
						(arc
							(start 0.3302 0.4318)
							(mid 0.402042 0.402042)
							(end 0.4318 0.3302)
						)
						(arc
							(start 0.4318 -0.3302)
							(mid 0.402042 -0.402042)
							(end 0.3302 -0.4318)
						)
					)
					(width 0)
					(fill yes)
				)
			)
		)
	)
	(footprint ""
		(layer "F.Cu")
		(at 238.252 -23.241)
		(property "Reference" "R796"
			(at 0 0 0)
			(layer "F.SilkS")
			(hide yes)
			(effects
				(font
					(size 1.27 1.27)
				)
			)
		)
		(property "Value" "4K7R2F-GP"
			(at 0.064008 -3.993896 0)
			(unlocked yes)
			(layer "F.Fab")
			(hide yes)
			(effects
				(font
					(size 1.016 1.016)
					(thickness 0.1524)
				)
			)
		)
		(property "Device Type" "R402H16"
			(at 0.064008 -5.517896 0)
			(unlocked yes)
			(layer "F.Fab")
			(hide yes)
			(effects
				(font
					(size 1.016 1.016)
					(thickness 0.1524)
				)
			)
		)
		(duplicate_pad_numbers_are_jumpers no)
		(fp_line
			(start -0.508 -0.9398)
			(end -0.508 0.9398)
			(stroke
				(width 0.1524)
				(type default)
			)
			(layer "F.SilkS")
		)
		(fp_line
			(start 0.508 -0.9398)
			(end -0.508 -0.9398)
			(stroke
				(width 0.1524)
				(type default)
			)
			(layer "F.SilkS")
		)
		(fp_rect
			(start -0.508 0.9398)
			(end 0.508 -0.9398)
			(stroke
				(width 0)
				(type default)
			)
			(fill no)
			(layer "F.CrtYd")
		)
		(fp_rect
			(start -0.508 0.9398)
			(end 0.508 -0.9398)
			(stroke
				(width 0)
				(type default)
			)
			(fill no)
			(layer "F.Fab")
		)
		(pad "1" smd custom
			(at 0 -0.4445)
			(size 0.1397 0.1397)
			(layers "F.Cu" "F.Mask" "F.Paste")
			(net "GND")
			(options
				(clearance outline)
				(anchor circle)
			)
			(primitives
				(gr_poly
					(pts
						(arc
							(start -0.1778 -0.2794)
							(mid -0.249642 -0.249642)
							(end -0.2794 -0.1778)
						)
						(arc
							(start -0.2794 0.1778)
							(mid -0.249642 0.249642)
							(end -0.1778 0.2794)
						)
						(arc
							(start 0.1778 0.2794)
							(mid 0.249642 0.249642)
							(end 0.2794 0.1778)
						)
						(arc
							(start 0.2794 -0.1778)
							(mid 0.249642 -0.249642)
							(end 0.1778 -0.2794)
						)
					)
					(width 0)
					(fill yes)
				)
			)
		)
		(pad "2" smd custom
			(at 0 0.4445)
			(size 0.1397 0.1397)
			(layers "F.Cu" "F.Mask" "F.Paste")
			(net "BOOTSTRAP2")
			(options
				(clearance outline)
				(anchor circle)
			)
			(primitives
				(gr_poly
					(pts
						(arc
							(start -0.1778 -0.2794)
							(mid -0.249642 -0.249642)
							(end -0.2794 -0.1778)
						)
						(arc
							(start -0.2794 0.1778)
							(mid -0.249642 0.249642)
							(end -0.1778 0.2794)
						)
						(arc
							(start 0.1778 0.2794)
							(mid 0.249642 0.249642)
							(end 0.2794 0.1778)
						)
						(arc
							(start 0.2794 -0.1778)
							(mid 0.249642 -0.249642)
							(end 0.1778 -0.2794)
						)
					)
					(width 0)
					(fill yes)
				)
			)
		)
	)
)
